G04 ================== begin FILE IDENTIFICATION RECORD ==================*
G04 Layout Name:  13130-1b.brd*
G04 Film Name:    WSILK_B*
G04 File Format:  Gerber RS274X*
G04 File Origin:  Cadence Allegro 16.5-S037*
G04 Origin Date:  Thu Nov 13 17:26:44 2014*
G04 *
G04 Layer:  DRAWING FORMAT/LAYER_WSILK_B*
G04 Layer:  DRAWING FORMAT/LAYER_PCB_STORY*
G04 Layer:  BOARD GEOMETRY/WSILK_B*
G04 Layer:  BOARD GEOMETRY/PANEL_OUTLINE*
G04 *
G04 Offset:    (0.00 0.00)*
G04 Mirror:    No*
G04 Mode:      Positive*
G04 Rotation:  0*
G04 FullContactRelief:  No*
G04 UndefLineWidth:     6.00*
G04 ================== end FILE IDENTIFICATION RECORD ====================*
%FSLAX35Y35*MOIN*%
%IR0*IPPOS*OFA0.00000B0.00000*MIA0B0*SFA1.00000B1.00000*%
%ADD10C,.02*%
%ADD11C,.006*%
G75*
%LPD*%
G75*
G54D10*
G01X10636Y-27865D02*
G02I-12000J0D01*
G01X14636D02*
X-17364D01*
G01X5486D02*
G02I-6850J0D01*
G01X-1364Y-43865D02*
Y-11865D01*
G01X14636Y-43865D02*
Y-123865D01*
G01D02*
X1309236D01*
G01X14636Y-79365D02*
X1309236D01*
G01X14636Y-43865D02*
X1309236D01*
G01X521736D02*
Y-123865D01*
G01X659236Y-43865D02*
Y-123865D01*
G01X774236Y-43865D02*
Y-123865D01*
G01X941736Y-43865D02*
Y-123865D01*
G01X1111736Y-43865D02*
Y-123865D01*
G01X1309236Y-43865D02*
Y-123865D01*
G01X1341236Y-27865D02*
X1309236D01*
G01X1337236D02*
G02I-12000J0D01*
G01X1332086D02*
G02I-6850J0D01*
G01X1325236Y-43865D02*
Y-11865D01*
G54D11*
G01X-31497Y-1D02*
X26377D01*
G01X-35434Y3936D02*
G03X-31497Y-1I3937J0D01*
G01X-35434Y585039D02*
Y3936D01*
G01X-7874Y588976D02*
X-31497D01*
G01D02*
G03X-35434Y585039I0J-3937D01*
G01X-12698Y15747D02*
G03I-6988J0D01*
G01Y573227D02*
G03I-6988J0D01*
G01X826773Y286614D02*
G03X822836Y290551I-3937J0D01*
G01X3938D01*
G03X1Y286614I0J-3937D01*
G01Y61811D01*
G03X3938Y57874I3937J0D01*
G01X53938D01*
G02X57875Y53937I0J-3937D01*
G01Y12598D01*
X59844Y10629D01*
X336222D01*
X338190Y12598D01*
Y39960D01*
G02X345671I3740J0D01*
G01Y12598D01*
X347639Y10629D01*
X387797D01*
X389765Y12598D01*
Y42126D01*
G02X393702Y46063I3937J0D01*
G01X409450D01*
G02X413387Y42126I0J-3937D01*
G01Y3937D01*
G03X417324Y0I3937J0D01*
G01X822836D01*
G03X826773Y3937I0J3937D01*
G01Y286614D01*
G01X22440Y49999D02*
X-3937D01*
G01X-7874Y53936D02*
Y72440D01*
G01Y53936D02*
G03X-3937Y49999I3937J0D01*
G01X0Y72440D02*
G03X-7874I-3937J0D01*
G01Y103149D02*
G03X0I3937J0D01*
G01X-7874D02*
Y210235D01*
G01X0D02*
G03X-7874I-3937J0D01*
G01Y240944D02*
Y348031D01*
G01Y240944D02*
G03X0I3937J0D01*
G01X-3Y302361D02*
G03X3934Y298424I3937J0D01*
G01X822832D01*
G03X826769Y302361I0J3937D01*
G01Y527164D01*
G03X822832Y531101I-3937J0D01*
G01X772832D01*
G02X768895Y535038I0J3937D01*
G01Y576377D01*
X766926Y578346D01*
X490548D01*
X488580Y576377D01*
Y549015D01*
G02X481099I-3740J0D01*
G01Y576377D01*
X479131Y578346D01*
X438973D01*
X437005Y576377D01*
Y546849D01*
G02X433068Y542912I-3937J0D01*
G01X417320D01*
G02X413383Y546849I0J3937D01*
G01Y585038D01*
G03X409446Y588975I-3937J0D01*
G01X3934D01*
G03X-3Y585038I0J-3937D01*
G01Y302361D01*
G01X0Y348031D02*
G03X-7874I-3937J0D01*
G01Y378739D02*
Y485826D01*
G01Y378739D02*
G03X0I3937J0D01*
G01Y485826D02*
G03X-7874I-3937J0D01*
G01Y516535D02*
Y588976D01*
G01Y516535D02*
G03X0I3937J-1D01*
G01X26377Y-1D02*
Y46062D01*
G01D02*
G03X22440Y49999I-3937J0D01*
G01X70851Y-113865D02*
Y-96365D01*
G01X80021D02*
Y-113865D01*
G01Y-105115D02*
X70851D01*
G01X92936Y-113865D02*
X91626Y-113573D01*
X90316Y-112407D01*
X89442Y-110365D01*
X89006Y-108032D01*
X89442Y-105698D01*
X90316Y-103657D01*
X91626Y-102490D01*
X92936Y-102199D01*
X94246Y-102490D01*
X95556Y-103657D01*
X96429Y-105698D01*
X96648Y-108032D01*
X96429Y-110365D01*
X95556Y-112407D01*
X94246Y-113573D01*
X92936Y-113865D01*
G01X106724D02*
Y-102199D01*
G01Y-105115D02*
X107598Y-103657D01*
X108908Y-102490D01*
X110654Y-102199D01*
X112182Y-102490D01*
X113493Y-103657D01*
X114148Y-105698D01*
Y-113865D01*
G01X124661Y-105990D02*
X131648D01*
X130993Y-103948D01*
X129901Y-102782D01*
X128373Y-102199D01*
X126844Y-102490D01*
X125534Y-103365D01*
X124661Y-105407D01*
X124224Y-107157D01*
Y-108907D01*
X124661Y-110657D01*
X125753Y-112407D01*
X127063Y-113573D01*
X128591Y-113865D01*
X130119Y-113282D01*
X131648Y-111532D01*
G01X140851Y-119115D02*
X142161Y-119698D01*
X143908Y-119115D01*
X144999Y-117949D01*
X145873Y-116490D01*
X147182Y-111824D01*
X150021Y-102199D01*
G01X143034D02*
X147182Y-111824D01*
G01X182182Y-104532D02*
X183056Y-103657D01*
X183711Y-102199D01*
X184148Y-100156D01*
X183711Y-98407D01*
X182838Y-97240D01*
X181309Y-96365D01*
X175414D01*
Y-113865D01*
X182619D01*
X184148Y-112699D01*
X185021Y-110948D01*
X185458Y-108907D01*
X185021Y-106865D01*
X183711Y-105115D01*
X182182Y-104532D01*
X175414D01*
G01X201866Y-113865D02*
Y-102199D01*
G01Y-104240D02*
X200993Y-103074D01*
X199682Y-102490D01*
X198154Y-102199D01*
X196626Y-102782D01*
X195316Y-103948D01*
X194442Y-105698D01*
X194006Y-108032D01*
X194442Y-110365D01*
X195316Y-112115D01*
X196626Y-113282D01*
X198154Y-113865D01*
X199682Y-113573D01*
X200993Y-112699D01*
X201866Y-111532D01*
G01X219366Y-96365D02*
Y-113865D01*
G01Y-111241D02*
X218493Y-112699D01*
X217182Y-113573D01*
X215654Y-113865D01*
X213908Y-113282D01*
X212598Y-111824D01*
X211724Y-110074D01*
X211506Y-108032D01*
X211724Y-105990D01*
X212598Y-104240D01*
X213908Y-102782D01*
X215654Y-102199D01*
X217182Y-102490D01*
X218274Y-103074D01*
X219366Y-104240D01*
G01X229879Y-118240D02*
X231408Y-119407D01*
X233154Y-119698D01*
X234682Y-119407D01*
X235993Y-117949D01*
X236866Y-115907D01*
Y-102199D01*
G01Y-104532D02*
X235993Y-103365D01*
X234682Y-102490D01*
X233154Y-102199D01*
X231408Y-102782D01*
X230316Y-103948D01*
X229442Y-105990D01*
X229006Y-108032D01*
X229224Y-109782D01*
X230098Y-111824D01*
X231408Y-113282D01*
X233154Y-113865D01*
X234464Y-113573D01*
X235993Y-112407D01*
X236866Y-111241D01*
G01X247161Y-105990D02*
X254148D01*
X253493Y-103948D01*
X252401Y-102782D01*
X250873Y-102199D01*
X249344Y-102490D01*
X248034Y-103365D01*
X247161Y-105407D01*
X246724Y-107157D01*
Y-108907D01*
X247161Y-110657D01*
X248253Y-112407D01*
X249563Y-113573D01*
X251091Y-113865D01*
X252619Y-113282D01*
X254148Y-111532D01*
G01X264879Y-113865D02*
Y-102199D01*
G01Y-104532D02*
X265971Y-103365D01*
X267063Y-102490D01*
X268591Y-102199D01*
X269682Y-102490D01*
X270993Y-103365D01*
G01X298569Y-113865D02*
Y-96365D01*
X303809D01*
X305556Y-97240D01*
X306866Y-99282D01*
X307303Y-101615D01*
X306866Y-103948D01*
X305774Y-105698D01*
X303809Y-106574D01*
X298569D01*
G01X324366Y-113865D02*
Y-102199D01*
G01Y-104240D02*
X323493Y-103074D01*
X322182Y-102490D01*
X320654Y-102199D01*
X319126Y-102782D01*
X317816Y-103948D01*
X316942Y-105698D01*
X316506Y-108032D01*
X316942Y-110365D01*
X317816Y-112115D01*
X319126Y-113282D01*
X320654Y-113865D01*
X322182Y-113573D01*
X323493Y-112699D01*
X324366Y-111532D01*
G01X334224Y-113865D02*
Y-102199D01*
G01Y-105115D02*
X335098Y-103657D01*
X336408Y-102490D01*
X338154Y-102199D01*
X339682Y-102490D01*
X340993Y-103657D01*
X341648Y-105698D01*
Y-113865D01*
G01X355436Y-96365D02*
Y-113865D01*
G01X352379Y-102199D02*
X358493D01*
G01X369224Y-113865D02*
Y-96365D01*
G01Y-104823D02*
X370316Y-103365D01*
X371408Y-102490D01*
X373154Y-102199D01*
X374464Y-102490D01*
X375993Y-103657D01*
X376648Y-105407D01*
Y-113865D01*
G01X387161Y-105990D02*
X394148D01*
X393493Y-103948D01*
X392401Y-102782D01*
X390873Y-102199D01*
X389344Y-102490D01*
X388034Y-103365D01*
X387161Y-105407D01*
X386724Y-107157D01*
Y-108907D01*
X387161Y-110657D01*
X388253Y-112407D01*
X389563Y-113573D01*
X391091Y-113865D01*
X392619Y-113282D01*
X394148Y-111532D01*
G01X404879Y-113865D02*
Y-102199D01*
G01Y-104532D02*
X405971Y-103365D01*
X407063Y-102490D01*
X408591Y-102199D01*
X409682Y-102490D01*
X410993Y-103365D01*
G01X437259Y-113865D02*
Y-96365D01*
X442936Y-110948D01*
X448613Y-96365D01*
Y-113865D01*
G01X462182Y-104532D02*
X463056Y-103657D01*
X463711Y-102199D01*
X464148Y-100156D01*
X463711Y-98407D01*
X462838Y-97240D01*
X461309Y-96365D01*
X455414D01*
Y-113865D01*
X462619D01*
X464148Y-112699D01*
X465021Y-110948D01*
X465458Y-108907D01*
X465021Y-106865D01*
X463711Y-105115D01*
X462182Y-104532D01*
X455414D01*
G01X102756Y290550D02*
G03Y298424I0J3937D01*
G01X133465D02*
G03Y290550I0J-3937D01*
G01X227259Y-68865D02*
Y-51365D01*
X232936Y-65948D01*
X238613Y-51365D01*
Y-68865D01*
G01X250436D02*
X249126Y-68573D01*
X247816Y-67407D01*
X246942Y-65365D01*
X246506Y-63032D01*
X246942Y-60698D01*
X247816Y-58657D01*
X249126Y-57490D01*
X250436Y-57199D01*
X251746Y-57490D01*
X253056Y-58657D01*
X253929Y-60698D01*
X254148Y-63032D01*
X253929Y-65365D01*
X253056Y-67407D01*
X251746Y-68573D01*
X250436Y-68865D01*
G01X271866Y-51365D02*
Y-68865D01*
G01Y-66241D02*
X270993Y-67699D01*
X269682Y-68573D01*
X268154Y-68865D01*
X266408Y-68282D01*
X265098Y-66824D01*
X264224Y-65074D01*
X264006Y-63032D01*
X264224Y-60990D01*
X265098Y-59240D01*
X266408Y-57782D01*
X268154Y-57199D01*
X269682Y-57490D01*
X270774Y-58074D01*
X271866Y-59240D01*
G01X282161Y-60990D02*
X289148D01*
X288493Y-58948D01*
X287401Y-57782D01*
X285873Y-57199D01*
X284344Y-57490D01*
X283034Y-58365D01*
X282161Y-60407D01*
X281724Y-62157D01*
Y-63907D01*
X282161Y-65657D01*
X283253Y-67407D01*
X284563Y-68573D01*
X286091Y-68865D01*
X287619Y-68282D01*
X289148Y-66532D01*
G01X302936Y-68865D02*
Y-51365D01*
G01X299606Y290551D02*
G03Y298425I0J3937D01*
G01X330314D02*
G03Y290551I0J-3937D01*
G01X496457Y290550D02*
G03Y298424I0J3937D01*
G01X527166D02*
G03Y290550I0J-3937D01*
G01X542319Y-68865D02*
Y-51365D01*
X547559D01*
X549306Y-52240D01*
X550616Y-54282D01*
X551053Y-56615D01*
X550616Y-58948D01*
X549524Y-60698D01*
X547559Y-61574D01*
X542319D01*
G01X568989Y-52824D02*
X567679Y-51948D01*
X566151Y-51365D01*
X564404D01*
X562439Y-52240D01*
X560911Y-53698D01*
X559819Y-55449D01*
X558946Y-58365D01*
X558727Y-60990D01*
X559164Y-63615D01*
X559819Y-65365D01*
X561129Y-67115D01*
X562658Y-68282D01*
X564186Y-68865D01*
X565714D01*
X567243Y-68282D01*
X568553Y-67407D01*
X569645Y-66241D01*
G01X583432Y-59532D02*
X584306Y-58657D01*
X584961Y-57199D01*
X585398Y-55156D01*
X584961Y-53407D01*
X584088Y-52240D01*
X582559Y-51365D01*
X576664D01*
Y-68865D01*
X583869D01*
X585398Y-67699D01*
X586271Y-65948D01*
X586708Y-63907D01*
X586271Y-61865D01*
X584961Y-60115D01*
X583432Y-59532D01*
X576664D01*
G01X592636Y-74698D02*
X605736D01*
G01X611664Y-68865D02*
Y-51365D01*
X621708Y-68865D01*
Y-51365D01*
G01X634186Y-68865D02*
X632439Y-68573D01*
X630911Y-67407D01*
X629601Y-65657D01*
X628727Y-63615D01*
X628291Y-61282D01*
Y-58948D01*
X628727Y-56615D01*
X629601Y-54573D01*
X630911Y-52824D01*
X632439Y-51657D01*
X634186Y-51365D01*
X635932Y-51657D01*
X637461Y-52824D01*
X638771Y-54573D01*
X639645Y-56615D01*
X640081Y-58948D01*
Y-61282D01*
X639645Y-63615D01*
X638771Y-65657D01*
X637461Y-67407D01*
X635932Y-68573D01*
X634186Y-68865D01*
G01X555436Y-113865D02*
Y-96365D01*
X552816Y-99865D01*
G01Y-113865D02*
X558056D01*
G01X568133Y-110365D02*
X569442Y-112407D01*
X571189Y-113573D01*
X573154Y-113865D01*
X574901Y-113573D01*
X576648Y-112115D01*
X577739Y-110365D01*
X577958Y-108615D01*
X577521Y-106574D01*
X575993Y-105115D01*
X574464Y-104532D01*
X572499D01*
G01X574464D02*
X575774Y-103657D01*
X576866Y-102199D01*
X577303Y-100449D01*
X576866Y-98698D01*
X575774Y-97240D01*
X573809Y-96365D01*
X571844Y-96657D01*
X569879Y-97824D01*
G01X590436Y-113865D02*
Y-96365D01*
X587816Y-99865D01*
G01Y-113865D02*
X593056D01*
G01X603133Y-110365D02*
X604442Y-112407D01*
X606189Y-113573D01*
X608154Y-113865D01*
X609901Y-113573D01*
X611648Y-112115D01*
X612739Y-110365D01*
X612958Y-108615D01*
X612521Y-106574D01*
X610993Y-105115D01*
X609464Y-104532D01*
X607499D01*
G01X609464D02*
X610774Y-103657D01*
X611866Y-102199D01*
X612303Y-100449D01*
X611866Y-98698D01*
X610774Y-97240D01*
X608809Y-96365D01*
X606844Y-96657D01*
X604879Y-97824D01*
G01X625436Y-96365D02*
X623689Y-96948D01*
X622379Y-98407D01*
X621506Y-100156D01*
X620851Y-102490D01*
X620633Y-105115D01*
X620851Y-107740D01*
X621506Y-110074D01*
X622379Y-111824D01*
X623689Y-113282D01*
X625436Y-113865D01*
X627182Y-113282D01*
X628493Y-111824D01*
X629366Y-110074D01*
X630021Y-107740D01*
X630239Y-105115D01*
X630021Y-102490D01*
X629366Y-100156D01*
X628493Y-98407D01*
X627182Y-96948D01*
X625436Y-96365D01*
G01X685027Y-51365D02*
X690486Y-68865D01*
X695945Y-51365D01*
G01X712353Y-68865D02*
X703619D01*
Y-51365D01*
X712353D01*
G01X708859Y-59823D02*
X703619D01*
G01X721119Y-68865D02*
Y-51365D01*
X726578D01*
X728324Y-52240D01*
X729416Y-53407D01*
X729853Y-55740D01*
X729416Y-58074D01*
X728106Y-59532D01*
X726578Y-60407D01*
X721119D01*
G01X726578D02*
X729853Y-68865D01*
G01X742986Y-69448D02*
X742549Y-69157D01*
Y-68573D01*
X742986Y-68282D01*
X743423Y-68573D01*
Y-69157D01*
X742986Y-69448D01*
G01X693308Y290550D02*
G03Y298424I0J3937D01*
G01X707986Y-113865D02*
Y-96365D01*
X705366Y-99865D01*
G01Y-113865D02*
X710606D01*
G01X727232Y-104532D02*
X728106Y-103657D01*
X728761Y-102199D01*
X729198Y-100156D01*
X728761Y-98407D01*
X727888Y-97240D01*
X726359Y-96365D01*
X720464D01*
Y-113865D01*
X727669D01*
X729198Y-112699D01*
X730071Y-110948D01*
X730508Y-108907D01*
X730071Y-106865D01*
X728761Y-105115D01*
X727232Y-104532D01*
X720464D01*
G01X724016Y298424D02*
G03Y290550I0J-3937D01*
G01X800393Y588976D02*
Y542913D01*
G01D02*
G03X804330Y538976I3937J0D01*
G01X858267Y588976D02*
X800393D01*
G01X818569Y-51365D02*
Y-68865D01*
X827303D01*
G01X844366D02*
Y-57199D01*
G01Y-59240D02*
X843493Y-58074D01*
X842182Y-57490D01*
X840654Y-57199D01*
X839126Y-57782D01*
X837816Y-58948D01*
X836942Y-60698D01*
X836506Y-63032D01*
X836942Y-65365D01*
X837816Y-67115D01*
X839126Y-68282D01*
X840654Y-68865D01*
X842182Y-68573D01*
X843493Y-67699D01*
X844366Y-66532D01*
G01X853351Y-74115D02*
X854661Y-74698D01*
X856408Y-74115D01*
X857499Y-72949D01*
X858373Y-71490D01*
X859682Y-66824D01*
X862521Y-57199D01*
G01X855534D02*
X859682Y-66824D01*
G01X872161Y-60990D02*
X879148D01*
X878493Y-58948D01*
X877401Y-57782D01*
X875873Y-57199D01*
X874344Y-57490D01*
X873034Y-58365D01*
X872161Y-60407D01*
X871724Y-62157D01*
Y-63907D01*
X872161Y-65657D01*
X873253Y-67407D01*
X874563Y-68573D01*
X876091Y-68865D01*
X877619Y-68282D01*
X879148Y-66532D01*
G01X889879Y-68865D02*
Y-57199D01*
G01Y-59532D02*
X890971Y-58365D01*
X892063Y-57490D01*
X893591Y-57199D01*
X894682Y-57490D01*
X895993Y-58365D01*
G01X804330Y538976D02*
X830708D01*
G01X834645Y72440D02*
G03X826771I-3937J0D01*
G01Y103149D02*
G03X834645I3937J0D01*
G01Y210235D02*
G03X826771I-3937J0D01*
G01Y240944D02*
G03X834645I3937J0D01*
G01Y348031D02*
G03X826771I-3937J0D01*
G01Y378739D02*
G03X834645I3937J0D01*
G01Y485826D02*
G03X826771I-3937J0D01*
G01Y516535D02*
G03X834645I3937J-1D01*
G01Y535039D02*
G03X830708Y538976I-3937J0D01*
G01X834645Y72440D02*
Y-1D01*
G01D02*
X858267D01*
G01X853444Y15747D02*
G03I-6988J0D01*
G01X834645Y210235D02*
Y103149D01*
G01Y348031D02*
Y240944D01*
G01Y485826D02*
Y378739D01*
G01Y535039D02*
Y516535D01*
G01X853444Y573227D02*
G03I-6988J0D01*
G01X862204Y3936D02*
Y585039D01*
G01X858267Y-1D02*
G03X862204Y3936I0J3937D01*
G01Y585039D02*
G03X858267Y588976I-3937J0D01*
G01X943619Y-110365D02*
X944711Y-112115D01*
X946021Y-113282D01*
X947549Y-113865D01*
X949296Y-113282D01*
X950606Y-112115D01*
X951916Y-110365D01*
X952353Y-108032D01*
Y-96365D01*
G01X965486Y-113865D02*
X963739Y-113573D01*
X962211Y-112407D01*
X960901Y-110657D01*
X960027Y-108615D01*
X959591Y-106282D01*
Y-103948D01*
X960027Y-101615D01*
X960901Y-99573D01*
X962211Y-97824D01*
X963739Y-96657D01*
X965486Y-96365D01*
X967232Y-96657D01*
X968761Y-97824D01*
X970071Y-99573D01*
X970945Y-101615D01*
X971381Y-103948D01*
Y-106282D01*
X970945Y-108615D01*
X970071Y-110657D01*
X968761Y-112407D01*
X967232Y-113573D01*
X965486Y-113865D01*
G01X978401Y-111532D02*
X980148Y-112990D01*
X982113Y-113865D01*
X983859D01*
X985606Y-112990D01*
X986916Y-111532D01*
X987571Y-109490D01*
X987134Y-107449D01*
X986043Y-105698D01*
X984078Y-104532D01*
X981458Y-103948D01*
X979929Y-102782D01*
X979274Y-100740D01*
X979711Y-98698D01*
X980803Y-97240D01*
X982331Y-96365D01*
X983859D01*
X985388Y-96948D01*
X986698Y-98407D01*
G01X1004853Y-113865D02*
X996119D01*
Y-96365D01*
X1004853D01*
G01X1001359Y-104823D02*
X996119D01*
G01X1013619Y-113865D02*
Y-96365D01*
X1018859D01*
X1020606Y-97240D01*
X1021916Y-99282D01*
X1022353Y-101615D01*
X1021916Y-103948D01*
X1020824Y-105698D01*
X1018859Y-106574D01*
X1013619D01*
G01X1030901Y-113865D02*
Y-96365D01*
G01X1040071D02*
Y-113865D01*
G01Y-105115D02*
X1030901D01*
G01X1066119Y-96365D02*
Y-113865D01*
X1074853D01*
G01X1082527D02*
X1087986Y-96365D01*
X1093445Y-113865D01*
G01X1091479Y-107740D02*
X1084492D01*
G01X1100683Y-96365D02*
Y-108907D01*
X1101556Y-111532D01*
X1103303Y-113282D01*
X1105486Y-113865D01*
X1107669Y-113282D01*
X1109416Y-111532D01*
X1110289Y-108907D01*
Y-96365D01*
G01X960683Y-68865D02*
Y-51365D01*
X965049D01*
X966796Y-52240D01*
X968106Y-53407D01*
X969198Y-55156D01*
X970071Y-57199D01*
X970289Y-60115D01*
X970071Y-63032D01*
X969198Y-65074D01*
X968106Y-66824D01*
X966796Y-67990D01*
X965049Y-68865D01*
X960683D01*
G01X979711Y-60990D02*
X986698D01*
X986043Y-58948D01*
X984951Y-57782D01*
X983423Y-57199D01*
X981894Y-57490D01*
X980584Y-58365D01*
X979711Y-60407D01*
X979274Y-62157D01*
Y-63907D01*
X979711Y-65657D01*
X980803Y-67407D01*
X982113Y-68573D01*
X983641Y-68865D01*
X985169Y-68282D01*
X986698Y-66532D01*
G01X997211Y-66824D02*
X998303Y-67990D01*
X999831Y-68865D01*
X1001141D01*
X1002451Y-68282D01*
X1003324Y-67407D01*
X1003761Y-66241D01*
X1003543Y-64490D01*
X1002669Y-63615D01*
X998739Y-61865D01*
X997866Y-59823D01*
X998303Y-58365D01*
X999176Y-57490D01*
X1000486Y-57199D01*
X1001796Y-57490D01*
X1003106Y-58365D01*
G01X1017986Y-57199D02*
Y-68865D01*
G01Y-52532D02*
X1017549Y-52240D01*
Y-51657D01*
X1017986Y-51365D01*
X1018423Y-51657D01*
Y-52240D01*
X1017986Y-52532D01*
G01X1032429Y-73240D02*
X1033958Y-74407D01*
X1035704Y-74698D01*
X1037232Y-74407D01*
X1038543Y-72949D01*
X1039416Y-70907D01*
Y-57199D01*
G01Y-59532D02*
X1038543Y-58365D01*
X1037232Y-57490D01*
X1035704Y-57199D01*
X1033958Y-57782D01*
X1032866Y-58948D01*
X1031992Y-60990D01*
X1031556Y-63032D01*
X1031774Y-64782D01*
X1032648Y-66824D01*
X1033958Y-68282D01*
X1035704Y-68865D01*
X1037014Y-68573D01*
X1038543Y-67407D01*
X1039416Y-66241D01*
G01X1049274Y-68865D02*
Y-57199D01*
G01Y-60115D02*
X1050148Y-58657D01*
X1051458Y-57490D01*
X1053204Y-57199D01*
X1054732Y-57490D01*
X1056043Y-58657D01*
X1056698Y-60698D01*
Y-68865D01*
G01X1067211Y-60990D02*
X1074198D01*
X1073543Y-58948D01*
X1072451Y-57782D01*
X1070923Y-57199D01*
X1069394Y-57490D01*
X1068084Y-58365D01*
X1067211Y-60407D01*
X1066774Y-62157D01*
Y-63907D01*
X1067211Y-65657D01*
X1068303Y-67407D01*
X1069613Y-68573D01*
X1071141Y-68865D01*
X1072669Y-68282D01*
X1074198Y-66532D01*
G01X1084929Y-68865D02*
Y-57199D01*
G01Y-59532D02*
X1086021Y-58365D01*
X1087113Y-57490D01*
X1088641Y-57199D01*
X1089732Y-57490D01*
X1091043Y-58365D01*
G01X1131686Y-113865D02*
Y-96365D01*
X1129066Y-99865D01*
G01Y-113865D02*
X1134306D01*
G01X1149186D02*
Y-96365D01*
X1146566Y-99865D01*
G01Y-113865D02*
X1151806D01*
G01X1162756Y-114448D02*
X1170616Y-96365D01*
G01X1184186Y-113865D02*
Y-96365D01*
X1181566Y-99865D01*
G01Y-113865D02*
X1186806D01*
G01X1196883Y-110365D02*
X1198192Y-112407D01*
X1199939Y-113573D01*
X1201904Y-113865D01*
X1203651Y-113573D01*
X1205398Y-112115D01*
X1206489Y-110365D01*
X1206708Y-108615D01*
X1206271Y-106574D01*
X1204743Y-105115D01*
X1203214Y-104532D01*
X1201249D01*
G01X1203214D02*
X1204524Y-103657D01*
X1205616Y-102199D01*
X1206053Y-100449D01*
X1205616Y-98698D01*
X1204524Y-97240D01*
X1202559Y-96365D01*
X1200594Y-96657D01*
X1198629Y-97824D01*
G01X1215256Y-114448D02*
X1223116Y-96365D01*
G01X1232538Y-99282D02*
X1233848Y-97532D01*
X1235376Y-96657D01*
X1237123Y-96365D01*
X1239306Y-96948D01*
X1240834Y-98407D01*
X1241271Y-100156D01*
X1241053Y-101907D01*
X1240179Y-103365D01*
X1235813Y-106282D01*
X1233848Y-108323D01*
X1232538Y-111241D01*
X1232101Y-113865D01*
X1241271D01*
G01X1254186Y-96365D02*
X1252439Y-96948D01*
X1251129Y-98407D01*
X1250256Y-100156D01*
X1249601Y-102490D01*
X1249383Y-105115D01*
X1249601Y-107740D01*
X1250256Y-110074D01*
X1251129Y-111824D01*
X1252439Y-113282D01*
X1254186Y-113865D01*
X1255932Y-113282D01*
X1257243Y-111824D01*
X1258116Y-110074D01*
X1258771Y-107740D01*
X1258989Y-105115D01*
X1258771Y-102490D01*
X1258116Y-100156D01*
X1257243Y-98407D01*
X1255932Y-96948D01*
X1254186Y-96365D01*
G01X1271686Y-113865D02*
Y-96365D01*
X1269066Y-99865D01*
G01Y-113865D02*
X1274306D01*
G01X1291806D02*
Y-96365D01*
X1283727Y-108907D01*
X1294645D01*
G01X1179383Y-68865D02*
Y-51365D01*
X1183749D01*
X1185496Y-52240D01*
X1186806Y-53407D01*
X1187898Y-55156D01*
X1188771Y-57199D01*
X1188989Y-60115D01*
X1188771Y-63032D01*
X1187898Y-65074D01*
X1186806Y-66824D01*
X1185496Y-67990D01*
X1183749Y-68865D01*
X1179383D01*
G01X1205616D02*
Y-57199D01*
G01Y-59240D02*
X1204743Y-58074D01*
X1203432Y-57490D01*
X1201904Y-57199D01*
X1200376Y-57782D01*
X1199066Y-58948D01*
X1198192Y-60698D01*
X1197756Y-63032D01*
X1198192Y-65365D01*
X1199066Y-67115D01*
X1200376Y-68282D01*
X1201904Y-68865D01*
X1203432Y-68573D01*
X1204743Y-67699D01*
X1205616Y-66532D01*
G01X1219186Y-51365D02*
Y-68865D01*
G01X1216129Y-57199D02*
X1222243D01*
G01X1233411Y-60990D02*
X1240398D01*
X1239743Y-58948D01*
X1238651Y-57782D01*
X1237123Y-57199D01*
X1235594Y-57490D01*
X1234284Y-58365D01*
X1233411Y-60407D01*
X1232974Y-62157D01*
Y-63907D01*
X1233411Y-65657D01*
X1234503Y-67407D01*
X1235813Y-68573D01*
X1237341Y-68865D01*
X1238869Y-68282D01*
X1240398Y-66532D01*
G01X397500Y239500D02*
X399367Y246500D01*
X401500Y239500D01*
X403633Y246500D01*
X405500Y239500D01*
G01X410100Y241833D02*
Y246500D01*
G01Y239967D02*
X409833Y239850D01*
Y239617D01*
X410100Y239500D01*
X410367Y239617D01*
Y239850D01*
X410100Y239967D01*
G01X415367Y241833D02*
X416967Y246500D01*
X418700Y241833D01*
X420433Y246500D01*
X422033Y241833D01*
G01X424500Y248600D02*
X425300Y248833D01*
X426367Y248600D01*
X427033Y248133D01*
X427567Y247550D01*
X428367Y245684D01*
X430100Y241833D01*
G01X425833D02*
X428367Y245684D01*
G01X433633Y246500D02*
Y241833D01*
G01Y243000D02*
X434167Y242417D01*
X434967Y241950D01*
X436033Y241833D01*
X436967Y241950D01*
X437767Y242417D01*
X438167Y243233D01*
Y246500D01*
G01X442233D02*
Y241833D01*
G01Y243000D02*
X442767Y242417D01*
X443567Y241950D01*
X444633Y241833D01*
X445567Y241950D01*
X446367Y242417D01*
X446767Y243233D01*
Y246500D01*
G01X735833Y287500D02*
Y285000D01*
X736667D01*
X737000Y285125D01*
X737250Y285292D01*
X737458Y285542D01*
X737625Y285833D01*
X737667Y286250D01*
X737625Y286667D01*
X737458Y286958D01*
X737250Y287208D01*
X737000Y287375D01*
X736667Y287500D01*
X735833D01*
G01X738933D02*
Y285000D01*
X739767D01*
X740100Y285125D01*
X740350Y285292D01*
X740558Y285542D01*
X740725Y285833D01*
X740767Y286250D01*
X740725Y286667D01*
X740558Y286958D01*
X740350Y287208D01*
X740100Y287375D01*
X739767Y287500D01*
X738933D01*
G01X742117D02*
Y285000D01*
X743158D01*
X743492Y285125D01*
X743700Y285292D01*
X743783Y285625D01*
X743700Y285958D01*
X743450Y286167D01*
X743158Y286292D01*
X742117D01*
G01X743158D02*
X743783Y287500D01*
G01X750067Y285208D02*
X749817Y285083D01*
X749525Y285000D01*
X749192D01*
X748817Y285125D01*
X748525Y285333D01*
X748317Y285583D01*
X748150Y286000D01*
X748108Y286375D01*
X748192Y286750D01*
X748317Y287000D01*
X748567Y287250D01*
X748858Y287417D01*
X749150Y287500D01*
X749442D01*
X749733Y287417D01*
X749983Y287292D01*
X750192Y287125D01*
G01X751375Y287500D02*
Y285000D01*
G01X753125D02*
Y287500D01*
G01Y286250D02*
X751375D01*
G01X754308Y287500D02*
X755350Y285000D01*
X756392Y287500D01*
G01X756017Y286625D02*
X754683D01*
G01X757200Y288333D02*
X759700D01*
G01X761550Y285000D02*
X761217Y285083D01*
X760967Y285292D01*
X760800Y285542D01*
X760675Y285875D01*
X760633Y286250D01*
X760675Y286625D01*
X760800Y286958D01*
X760967Y287208D01*
X761217Y287417D01*
X761550Y287500D01*
X761883Y287417D01*
X762133Y287208D01*
X762300Y286958D01*
X762425Y286625D01*
X762467Y286250D01*
X762425Y285875D01*
X762300Y285542D01*
X762133Y285292D01*
X761883Y285083D01*
X761550Y285000D01*
G01X768917Y287500D02*
Y285000D01*
X769917D01*
X770250Y285125D01*
X770500Y285417D01*
X770583Y285750D01*
X770500Y286083D01*
X770292Y286333D01*
X769917Y286458D01*
X768917D01*
G01X771600Y285000D02*
X772183Y287500D01*
X772850Y285000D01*
X773517Y287500D01*
X774100Y285000D01*
G01X775117Y287500D02*
Y285000D01*
X776158D01*
X776492Y285125D01*
X776700Y285292D01*
X776783Y285625D01*
X776700Y285958D01*
X776450Y286167D01*
X776158Y286292D01*
X775117D01*
G01X776158D02*
X776783Y287500D01*
G01X813167Y2000D02*
Y4500D01*
X812333D01*
X812000Y4375D01*
X811750Y4208D01*
X811542Y3958D01*
X811375Y3667D01*
X811333Y3250D01*
X811375Y2833D01*
X811542Y2542D01*
X811750Y2292D01*
X812000Y2125D01*
X812333Y2000D01*
X813167D01*
G01X810067D02*
Y4500D01*
X809233D01*
X808900Y4375D01*
X808650Y4208D01*
X808442Y3958D01*
X808275Y3667D01*
X808233Y3250D01*
X808275Y2833D01*
X808442Y2542D01*
X808650Y2292D01*
X808900Y2125D01*
X809233Y2000D01*
X810067D01*
G01X806883D02*
Y4500D01*
X805842D01*
X805508Y4375D01*
X805300Y4208D01*
X805217Y3875D01*
X805300Y3542D01*
X805550Y3333D01*
X805842Y3208D01*
X806883D01*
G01X805842D02*
X805217Y2000D01*
G01X798933Y4292D02*
X799183Y4417D01*
X799475Y4500D01*
X799808D01*
X800183Y4375D01*
X800475Y4167D01*
X800683Y3917D01*
X800850Y3500D01*
X800892Y3125D01*
X800808Y2750D01*
X800683Y2500D01*
X800433Y2250D01*
X800142Y2083D01*
X799850Y2000D01*
X799558D01*
X799267Y2083D01*
X799017Y2208D01*
X798808Y2375D01*
G01X797625Y2000D02*
Y4500D01*
G01X795875D02*
Y2000D01*
G01Y3250D02*
X797625D01*
G01X793317Y3333D02*
X793150Y3458D01*
X793025Y3667D01*
X792942Y3958D01*
X793025Y4208D01*
X793192Y4375D01*
X793483Y4500D01*
X794608D01*
Y2000D01*
X793233D01*
X792942Y2167D01*
X792775Y2417D01*
X792692Y2708D01*
X792775Y3000D01*
X793025Y3250D01*
X793317Y3333D01*
X794608D01*
G01X791800Y1167D02*
X789300D01*
G01X787450Y4500D02*
X787783Y4417D01*
X788033Y4208D01*
X788200Y3958D01*
X788325Y3625D01*
X788367Y3250D01*
X788325Y2875D01*
X788200Y2542D01*
X788033Y2292D01*
X787783Y2083D01*
X787450Y2000D01*
X787117Y2083D01*
X786867Y2292D01*
X786700Y2542D01*
X786575Y2875D01*
X786533Y3250D01*
X786575Y3625D01*
X786700Y3958D01*
X786867Y4208D01*
X787117Y4417D01*
X787450Y4500D01*
G01X783833Y252000D02*
Y249500D01*
X784667D01*
X785000Y249625D01*
X785250Y249792D01*
X785458Y250042D01*
X785625Y250333D01*
X785667Y250750D01*
X785625Y251167D01*
X785458Y251458D01*
X785250Y251708D01*
X785000Y251875D01*
X784667Y252000D01*
X783833D01*
G01X787350Y249500D02*
X788350D01*
G01X787850D02*
Y252000D01*
G01X787350D02*
X788350D01*
G01X789908D02*
X790950Y249500D01*
X791992Y252000D01*
G01X791617Y251125D02*
X790283D01*
G01X794300Y250750D02*
X795133D01*
Y251500D01*
X794883Y251750D01*
X794592Y251917D01*
X794175Y252000D01*
X793758Y251917D01*
X793467Y251750D01*
X793217Y251500D01*
X793050Y251208D01*
X792967Y250875D01*
Y250583D01*
X793050Y250333D01*
X793217Y250042D01*
X793467Y249792D01*
X793717Y249625D01*
X794050Y249500D01*
X794342D01*
X794675Y249583D01*
X794925Y249750D01*
G01X796000Y117333D02*
Y114833D01*
G01Y115208D02*
X796208Y115000D01*
X796417Y114875D01*
X796750Y114833D01*
X797042Y114875D01*
X797333Y115083D01*
X797458Y115375D01*
X797500Y115667D01*
X797458Y115958D01*
X797333Y116250D01*
X797083Y116417D01*
X796750Y116500D01*
X796458Y116458D01*
X796167Y116333D01*
X796000Y116167D01*
G01X799850Y116500D02*
X799600Y116458D01*
X799350Y116292D01*
X799183Y116000D01*
X799100Y115667D01*
X799183Y115333D01*
X799350Y115042D01*
X799600Y114875D01*
X799850Y114833D01*
X800100Y114875D01*
X800350Y115042D01*
X800517Y115333D01*
X800558Y115667D01*
X800517Y116000D01*
X800350Y116292D01*
X800100Y116458D01*
X799850Y116500D01*
G01X802367D02*
Y114833D01*
G01Y115167D02*
X802575Y115000D01*
X802783Y114875D01*
X803075Y114833D01*
X803283Y114875D01*
X803533Y115000D01*
G01X806050Y114000D02*
Y116500D01*
G01X805467Y114833D02*
X806633D01*
G01X812250Y116500D02*
X812542Y116458D01*
X812875Y116333D01*
X813083Y116125D01*
X813167Y115833D01*
X813083Y115542D01*
X812833Y115292D01*
X812458Y115167D01*
X812042D01*
X811792Y115083D01*
X811583Y114875D01*
X811500Y114583D01*
X811625Y114292D01*
X811917Y114083D01*
X812250Y114000D01*
X812583Y114083D01*
X812875Y114292D01*
X813000Y114583D01*
X812917Y114875D01*
X812708Y115083D01*
X812458Y115167D01*
X812042D01*
X811667Y115292D01*
X811417Y115542D01*
X811333Y115833D01*
X811417Y116125D01*
X811625Y116333D01*
X811958Y116458D01*
X812250Y116500D01*
G01X815350Y114000D02*
X815017Y114083D01*
X814767Y114292D01*
X814600Y114542D01*
X814475Y114875D01*
X814433Y115250D01*
X814475Y115625D01*
X814600Y115958D01*
X814767Y116208D01*
X815017Y116417D01*
X815350Y116500D01*
X815683Y116417D01*
X815933Y116208D01*
X816100Y115958D01*
X816225Y115625D01*
X816267Y115250D01*
X816225Y114875D01*
X816100Y114542D01*
X815933Y114292D01*
X815683Y114083D01*
X815350Y114000D01*
G01X798083Y272167D02*
X798250Y272042D01*
X798375Y271833D01*
X798458Y271542D01*
X798375Y271292D01*
X798208Y271125D01*
X797917Y271000D01*
X796792D01*
Y273500D01*
X798167D01*
X798458Y273333D01*
X798625Y273083D01*
X798708Y272792D01*
X798625Y272500D01*
X798375Y272250D01*
X798083Y272167D01*
X796792D01*
G01X801683Y273500D02*
X800017D01*
Y271000D01*
X801683D01*
G01X801017Y272208D02*
X800017D01*
G01X804783Y273500D02*
X803117D01*
Y271000D01*
X804783D01*
G01X804117Y272208D02*
X803117D01*
G01X806217Y273500D02*
Y271000D01*
X807217D01*
X807550Y271125D01*
X807800Y271417D01*
X807883Y271750D01*
X807800Y272083D01*
X807592Y272333D01*
X807217Y272458D01*
X806217D01*
G01X810917Y119500D02*
Y122000D01*
X812583D01*
G01X813975Y121667D02*
X814308Y121875D01*
X814683Y122000D01*
X815017D01*
X815350Y121875D01*
X815600Y121667D01*
X815725Y121375D01*
X815642Y121083D01*
X815433Y120833D01*
X815058Y120667D01*
X814558Y120583D01*
X814267Y120417D01*
X814142Y120125D01*
X814225Y119833D01*
X814433Y119625D01*
X814725Y119500D01*
X815017D01*
X815308Y119583D01*
X815558Y119792D01*
G01X818283Y120667D02*
X818450Y120542D01*
X818575Y120333D01*
X818658Y120042D01*
X818575Y119792D01*
X818408Y119625D01*
X818117Y119500D01*
X816992D01*
Y122000D01*
X818367D01*
X818658Y121833D01*
X818825Y121583D01*
X818908Y121292D01*
X818825Y121000D01*
X818575Y120750D01*
X818283Y120667D01*
X816992D01*
G01X810167Y173000D02*
Y170500D01*
X811250Y172583D01*
X812333Y170500D01*
Y173000D01*
G01X813475Y172667D02*
X813808Y172875D01*
X814183Y173000D01*
X814517D01*
X814850Y172875D01*
X815100Y172667D01*
X815225Y172375D01*
X815142Y172083D01*
X814933Y171833D01*
X814558Y171667D01*
X814058Y171583D01*
X813767Y171417D01*
X813642Y171125D01*
X813725Y170833D01*
X813933Y170625D01*
X814225Y170500D01*
X814517D01*
X814808Y170583D01*
X815058Y170792D01*
G01X817783Y171667D02*
X817950Y171542D01*
X818075Y171333D01*
X818158Y171042D01*
X818075Y170792D01*
X817908Y170625D01*
X817617Y170500D01*
X816492D01*
Y173000D01*
X817867D01*
X818158Y172833D01*
X818325Y172583D01*
X818408Y172292D01*
X818325Y172000D01*
X818075Y171750D01*
X817783Y171667D01*
X816492D01*
M02*
